# T6G (Grand Teton) — schematic netlist excerpt (pin names and nets, part order shuffled) for the footprints in the layout excerpt that follows; sources: Cadence DE-HDL packaged netlist, KiCad conversion of 04192023_DAF0TMB3IC0_F0TG_MB_C_brd_V02_OCP.brd

R494  Q_RES  0 5% CHIP  pkg 0402LF  page 188 : A = PWRGD_P5V_R_N ; B = PWRGD_P5V_N
C757  Q_CAP_DIFFBUS  DIFF BUS_0.22UF 6.3V 20% X6S  pkg C0201  page 66 : \1\ = P5E_CPU1_P2_TX_C_DP<8> ; \2\ = P5E_CPU1_P2_TX_DP<8>
R4554  Q_RES  100K 1% CHIP  pkg 0402LF  page 241 : A = P3V3_AUX ; B = HPDB_HSC_PWRGD_ISO

(kicad_pcb
	(version 20260206)
	(generator "pcbnew")
	(generator_version "10.0")
	(general
		(thickness 1.6)
		(legacy_teardrops no)
	)
	(paper "A4")
	(title_block
		(title "04192023_DAF0TMB3IC0_F0TG_MB_C_brd_V02_OCP.brd")
		(comment 1 "Grand Teton / footprints 3198-3200 of 8354")
	)
	(layers
		(0 "F.Cu" signal "TOP")
		(4 "In1.Cu" signal "GND")
		(6 "In2.Cu" signal "IN1")
		(8 "In3.Cu" signal "GND1")
		(10 "In4.Cu" signal "IN2")
		(12 "In5.Cu" signal "GND2")
		(14 "In6.Cu" signal "IN3")
		(16 "In7.Cu" signal "GND3")
		(18 "In8.Cu" signal "VCC")
		(20 "In9.Cu" signal "VCC1")
		(22 "In10.Cu" signal "GND4")
		(24 "In11.Cu" signal "IN4")
		(26 "In12.Cu" signal "GND5")
		(28 "In13.Cu" signal "IN5")
		(30 "In14.Cu" signal "GND6")
		(32 "In15.Cu" signal "IN6")
		(34 "In16.Cu" signal "GND7")
		(2 "B.Cu" signal "BOTTOM")
		(9 "F.Adhes" user "F.Adhesive")
		(11 "B.Adhes" user "B.Adhesive")
		(13 "F.Paste" user "Package Geometry/Pastemask Top")
		(15 "B.Paste" user "Package Geometry/Pastemask Bottom")
		(5 "F.SilkS" user "Ref Des/Silkscreen Top")
		(7 "B.SilkS" user "Ref Des/Silkscreen Bottom")
		(1 "F.Mask" user "Board Geometry/Soldermask Top")
		(3 "B.Mask" user "Board Geometry/Soldermask Bottom")
		(17 "Dwgs.User" user "User.Drawings")
		(19 "Cmts.User" user "User.Comments")
		(21 "Eco1.User" user "User.Eco1")
		(23 "Eco2.User" user "User.Eco2")
		(25 "Edge.Cuts" user "Board Geometry/Outline")
		(27 "Margin" user)
		(31 "F.CrtYd" user "Package Geometry/Place Bound Top")
		(29 "B.CrtYd" user "Package Geometry/Place Bound Bottom")
		(35 "F.Fab" user "Ref Des/Assembly Top")
		(33 "B.Fab" user "Ref Des/Assembly Bottom")
	)
	(footprint ""
		(layer "F.Cu")
		(at 279.022556 -436.223664 90)
		(property "Reference" "R4554"
			(at 0 0 90)
			(layer "F.SilkS")
			(hide yes)
			(effects
				(font
					(size 1.27 1.27)
				)
			)
		)
		(property "Value" ""
			(at 0 0 90)
			(layer "F.Fab")
			(effects
				(font
					(size 1.27 1.27)
				)
			)
		)
		(duplicate_pad_numbers_are_jumpers no)
		(fp_line
			(start 0.7874 -0.4064)
			(end 0.7874 0.4064)
			(stroke
				(width 0.1524)
				(type default)
			)
			(layer "F.SilkS")
		)
		(fp_line
			(start -0.7874 -0.4064)
			(end 0.7874 -0.4064)
			(stroke
				(width 0.1524)
				(type default)
			)
			(layer "F.SilkS")
		)
		(fp_line
			(start 0.7874 0.4064)
			(end -0.7874 0.4064)
			(stroke
				(width 0.1524)
				(type default)
			)
			(layer "F.SilkS")
		)
		(fp_line
			(start -0.7874 0.4064)
			(end -0.7874 -0.4064)
			(stroke
				(width 0.1524)
				(type default)
			)
			(layer "F.SilkS")
		)
		(fp_line
			(start -0.12065 -0.305054)
			(end -0.12065 -0.2794)
			(stroke
				(width 0.1)
				(type default)
			)
			(layer "F.Fab")
		)
		(fp_line
			(start -0.67945 -0.305054)
			(end -0.12065 -0.305054)
			(stroke
				(width 0.1)
				(type default)
			)
			(layer "F.Fab")
		)
		(fp_line
			(start 0.67945 -0.3048)
			(end 0.67945 0.3048)
			(stroke
				(width 0.1)
				(type default)
			)
			(layer "F.Fab")
		)
		(fp_line
			(start 0.12065 -0.3048)
			(end 0.67945 -0.3048)
			(stroke
				(width 0.1)
				(type default)
			)
			(layer "F.Fab")
		)
		(fp_line
			(start 0.12065 -0.2794)
			(end 0.12065 -0.3048)
			(stroke
				(width 0.1)
				(type default)
			)
			(layer "F.Fab")
		)
		(fp_line
			(start -0.12065 -0.2794)
			(end 0.12065 -0.2794)
			(stroke
				(width 0.1)
				(type default)
			)
			(layer "F.Fab")
		)
		(fp_line
			(start 0.120396 0.2794)
			(end -0.12065 0.2794)
			(stroke
				(width 0.1)
				(type default)
			)
			(layer "F.Fab")
		)
		(fp_line
			(start -0.12065 0.2794)
			(end -0.12065 0.3048)
			(stroke
				(width 0.1)
				(type default)
			)
			(layer "F.Fab")
		)
		(fp_line
			(start 0.67945 0.3048)
			(end 0.120396 0.3048)
			(stroke
				(width 0.1)
				(type default)
			)
			(layer "F.Fab")
		)
		(fp_line
			(start 0.120396 0.3048)
			(end 0.120396 0.2794)
			(stroke
				(width 0.1)
				(type default)
			)
			(layer "F.Fab")
		)
		(fp_line
			(start -0.12065 0.3048)
			(end -0.67945 0.3048)
			(stroke
				(width 0.1)
				(type default)
			)
			(layer "F.Fab")
		)
		(fp_line
			(start -0.67945 0.3048)
			(end -0.67945 -0.305054)
			(stroke
				(width 0.1)
				(type default)
			)
			(layer "F.Fab")
		)
		(pad "1" smd circle
			(at -0.40005 0 90)
			(size 0 0)
			(layers "F.Cu" "F.Mask" "F.Paste")
			(net "P3V3_AUX")
		)
		(pad "2" smd circle
			(at 0.40005 0 90)
			(size 0 0)
			(layers "F.Cu" "F.Mask" "F.Paste")
			(net "HPDB_HSC_PWRGD_ISO")
		)
	)
	(footprint ""
		(layer "F.Cu")
		(at 166.624 -129.921 -90)
		(property "Reference" "R494"
			(at 0 0 270)
			(layer "F.SilkS")
			(hide yes)
			(effects
				(font
					(size 1.27 1.27)
				)
			)
		)
		(property "Value" ""
			(at 0 0 270)
			(layer "F.Fab")
			(effects
				(font
					(size 1.27 1.27)
				)
			)
		)
		(duplicate_pad_numbers_are_jumpers no)
		(fp_line
			(start -0.7874 0.4064)
			(end -0.7874 -0.4064)
			(stroke
				(width 0.1524)
				(type default)
			)
			(layer "F.SilkS")
		)
		(fp_line
			(start 0.7874 0.4064)
			(end -0.7874 0.4064)
			(stroke
				(width 0.1524)
				(type default)
			)
			(layer "F.SilkS")
		)
		(fp_line
			(start -0.7874 -0.4064)
			(end 0.7874 -0.4064)
			(stroke
				(width 0.1524)
				(type default)
			)
			(layer "F.SilkS")
		)
		(fp_line
			(start 0.7874 -0.4064)
			(end 0.7874 0.4064)
			(stroke
				(width 0.1524)
				(type default)
			)
			(layer "F.SilkS")
		)
		(fp_line
			(start -0.67945 0.3048)
			(end -0.67945 -0.305054)
			(stroke
				(width 0.1)
				(type default)
			)
			(layer "F.Fab")
		)
		(fp_line
			(start -0.12065 0.3048)
			(end -0.67945 0.3048)
			(stroke
				(width 0.1)
				(type default)
			)
			(layer "F.Fab")
		)
		(fp_line
			(start 0.120396 0.3048)
			(end 0.120396 0.2794)
			(stroke
				(width 0.1)
				(type default)
			)
			(layer "F.Fab")
		)
		(fp_line
			(start 0.67945 0.3048)
			(end 0.120396 0.3048)
			(stroke
				(width 0.1)
				(type default)
			)
			(layer "F.Fab")
		)
		(fp_line
			(start -0.12065 0.2794)
			(end -0.12065 0.3048)
			(stroke
				(width 0.1)
				(type default)
			)
			(layer "F.Fab")
		)
		(fp_line
			(start 0.120396 0.2794)
			(end -0.12065 0.2794)
			(stroke
				(width 0.1)
				(type default)
			)
			(layer "F.Fab")
		)
		(fp_line
			(start -0.12065 -0.2794)
			(end 0.12065 -0.2794)
			(stroke
				(width 0.1)
				(type default)
			)
			(layer "F.Fab")
		)
		(fp_line
			(start 0.12065 -0.2794)
			(end 0.12065 -0.3048)
			(stroke
				(width 0.1)
				(type default)
			)
			(layer "F.Fab")
		)
		(fp_line
			(start 0.12065 -0.3048)
			(end 0.67945 -0.3048)
			(stroke
				(width 0.1)
				(type default)
			)
			(layer "F.Fab")
		)
		(fp_line
			(start 0.67945 -0.3048)
			(end 0.67945 0.3048)
			(stroke
				(width 0.1)
				(type default)
			)
			(layer "F.Fab")
		)
		(fp_line
			(start -0.67945 -0.305054)
			(end -0.12065 -0.305054)
			(stroke
				(width 0.1)
				(type default)
			)
			(layer "F.Fab")
		)
		(fp_line
			(start -0.12065 -0.305054)
			(end -0.12065 -0.2794)
			(stroke
				(width 0.1)
				(type default)
			)
			(layer "F.Fab")
		)
		(pad "1" smd circle
			(at -0.40005 0 270)
			(size 0 0)
			(layers "F.Cu" "F.Mask" "F.Paste")
			(net "PWRGD_P5V_R_N")
		)
		(pad "2" smd circle
			(at 0.40005 0 270)
			(size 0 0)
			(layers "F.Cu" "F.Mask" "F.Paste")
			(net "PWRGD_P5V_N")
		)
	)
	(footprint ""
		(layer "F.Cu")
		(at 156.231844 -373.03583 -90)
		(property "Reference" "C757"
			(at 0 0 270)
			(layer "F.SilkS")
			(hide yes)
			(effects
				(font
					(size 1.27 1.27)
				)
			)
		)
		(property "Value" ""
			(at 0 0 270)
			(layer "F.Fab")
			(effects
				(font
					(size 1.27 1.27)
				)
			)
		)
		(duplicate_pad_numbers_are_jumpers no)
		(fp_line
			(start -0.299974 0.150114)
			(end -0.299974 -0.150114)
			(stroke
				(width 0.1)
				(type default)
			)
			(layer "F.Fab")
		)
		(fp_line
			(start 0.299974 0.150114)
			(end -0.299974 0.150114)
			(stroke
				(width 0.1)
				(type default)
			)
			(layer "F.Fab")
		)
		(fp_line
			(start -0.299974 -0.150114)
			(end 0.299974 -0.150114)
			(stroke
				(width 0.1)
				(type default)
			)
			(layer "F.Fab")
		)
		(fp_line
			(start 0.299974 -0.150114)
			(end 0.299974 0.150114)
			(stroke
				(width 0.1)
				(type default)
			)
			(layer "F.Fab")
		)
		(pad "1" smd rect
			(at -0.2667 0 270)
			(size 0.3048 0.381)
			(layers "F.Cu" "F.Mask" "F.Paste")
			(net "P5E_CPU1_P2_TX_C_DP<8>")
		)
		(pad "2" smd rect
			(at 0.2667 0 270)
			(size 0.3048 0.381)
			(layers "F.Cu" "F.Mask" "F.Paste")
			(net "P5E_CPU1_P2_TX_DP<8>")
		)
	)
)
